# T6G (Grand Teton) — schematic netlist excerpt (pin names and nets, part order shuffled) for the footprints in the layout excerpt that follows; sources: Cadence DE-HDL packaged netlist, KiCad conversion of 04192023_DAF0TMB3IC0_F0TG_MB_C_brd_V02_OCP.brd

C6560  Q_CAP_DIFFBUS  DIFF BUS_0.22UF 6.3V 20% X6S  pkg C0201  page 286 : \1\ = P5E_CPU0_P1_TX_BUF_C_DN<13> ; \2\ = P5E_CPU0_P1_TX_BUF_DN<13>
C2443  Q_CAP  22UF 4V 20% X6S  pkg C0402  page 74 : A = PVDDCR_SOC_P1 ; B = GND
C967  Q_CAP  4.7UF 6.3V 20% X6S  pkg 0402  page 301 : A = P0V9_CPU0_RT2_2A ; B = GND

(kicad_pcb
	(version 20260206)
	(generator "pcbnew")
	(generator_version "10.0")
	(general
		(thickness 1.6)
		(legacy_teardrops no)
	)
	(paper "A4")
	(title_block
		(title "04192023_DAF0TMB3IC0_F0TG_MB_C_brd_V02_OCP.brd")
		(comment 1 "Grand Teton / footprints 5393-5395 of 8354")
	)
	(layers
		(0 "F.Cu" signal "TOP")
		(4 "In1.Cu" signal "GND")
		(6 "In2.Cu" signal "IN1")
		(8 "In3.Cu" signal "GND1")
		(10 "In4.Cu" signal "IN2")
		(12 "In5.Cu" signal "GND2")
		(14 "In6.Cu" signal "IN3")
		(16 "In7.Cu" signal "GND3")
		(18 "In8.Cu" signal "VCC")
		(20 "In9.Cu" signal "VCC1")
		(22 "In10.Cu" signal "GND4")
		(24 "In11.Cu" signal "IN4")
		(26 "In12.Cu" signal "GND5")
		(28 "In13.Cu" signal "IN5")
		(30 "In14.Cu" signal "GND6")
		(32 "In15.Cu" signal "IN6")
		(34 "In16.Cu" signal "GND7")
		(2 "B.Cu" signal "BOTTOM")
		(9 "F.Adhes" user "F.Adhesive")
		(11 "B.Adhes" user "B.Adhesive")
		(13 "F.Paste" user "Package Geometry/Pastemask Top")
		(15 "B.Paste" user "Package Geometry/Pastemask Bottom")
		(5 "F.SilkS" user "Ref Des/Silkscreen Top")
		(7 "B.SilkS" user "Ref Des/Silkscreen Bottom")
		(1 "F.Mask" user "Board Geometry/Soldermask Top")
		(3 "B.Mask" user "Board Geometry/Soldermask Bottom")
		(17 "Dwgs.User" user "User.Drawings")
		(19 "Cmts.User" user "User.Comments")
		(21 "Eco1.User" user "User.Eco1")
		(23 "Eco2.User" user "User.Eco2")
		(25 "Edge.Cuts" user "Board Geometry/Outline")
		(27 "Margin" user)
		(31 "F.CrtYd" user "Package Geometry/Place Bound Top")
		(29 "B.CrtYd" user "Package Geometry/Place Bound Bottom")
		(35 "F.Fab" user "Ref Des/Assembly Top")
		(33 "B.Fab" user "Ref Des/Assembly Bottom")
	)
	(footprint ""
		(layer "B.Cu")
		(at 405.419052 -398.942052 90)
		(property "Reference" "C967"
			(at 0 0 90)
			(layer "B.SilkS")
			(hide yes)
			(effects
				(font
					(size 1.27 1.27)
				)
				(justify mirror)
			)
		)
		(property "Value" ""
			(at 0 0 90)
			(layer "B.Fab")
			(effects
				(font
					(size 1.27 1.27)
				)
				(justify mirror)
			)
		)
		(duplicate_pad_numbers_are_jumpers no)
		(fp_line
			(start 0.7874 -0.4064)
			(end -0.7874 -0.4064)
			(stroke
				(width 0.1524)
				(type default)
			)
			(layer "B.SilkS")
		)
		(fp_line
			(start -0.7874 -0.4064)
			(end -0.7874 0.4064)
			(stroke
				(width 0.1524)
				(type default)
			)
			(layer "B.SilkS")
		)
		(fp_line
			(start 0.7874 0.4064)
			(end 0.7874 -0.4064)
			(stroke
				(width 0.1524)
				(type default)
			)
			(layer "B.SilkS")
		)
		(fp_line
			(start -0.7874 0.4064)
			(end 0.7874 0.4064)
			(stroke
				(width 0.1524)
				(type default)
			)
			(layer "B.SilkS")
		)
		(fp_line
			(start 0.67945 -0.305054)
			(end 0.12065 -0.305054)
			(stroke
				(width 0.1)
				(type default)
			)
			(layer "B.Fab")
		)
		(fp_line
			(start 0.12065 -0.305054)
			(end 0.12065 -0.2794)
			(stroke
				(width 0.1)
				(type default)
			)
			(layer "B.Fab")
		)
		(fp_line
			(start -0.12065 -0.3048)
			(end -0.67945 -0.3048)
			(stroke
				(width 0.1)
				(type default)
			)
			(layer "B.Fab")
		)
		(fp_line
			(start -0.67945 -0.3048)
			(end -0.67945 0.3048)
			(stroke
				(width 0.1)
				(type default)
			)
			(layer "B.Fab")
		)
		(fp_line
			(start 0.12065 -0.2794)
			(end -0.12065 -0.2794)
			(stroke
				(width 0.1)
				(type default)
			)
			(layer "B.Fab")
		)
		(fp_line
			(start -0.12065 -0.2794)
			(end -0.12065 -0.3048)
			(stroke
				(width 0.1)
				(type default)
			)
			(layer "B.Fab")
		)
		(fp_line
			(start 0.12065 0.2794)
			(end 0.12065 0.3048)
			(stroke
				(width 0.1)
				(type default)
			)
			(layer "B.Fab")
		)
		(fp_line
			(start -0.120396 0.2794)
			(end 0.12065 0.2794)
			(stroke
				(width 0.1)
				(type default)
			)
			(layer "B.Fab")
		)
		(fp_line
			(start 0.67945 0.3048)
			(end 0.67945 -0.305054)
			(stroke
				(width 0.1)
				(type default)
			)
			(layer "B.Fab")
		)
		(fp_line
			(start 0.12065 0.3048)
			(end 0.67945 0.3048)
			(stroke
				(width 0.1)
				(type default)
			)
			(layer "B.Fab")
		)
		(fp_line
			(start -0.120396 0.3048)
			(end -0.120396 0.2794)
			(stroke
				(width 0.1)
				(type default)
			)
			(layer "B.Fab")
		)
		(fp_line
			(start -0.67945 0.3048)
			(end -0.120396 0.3048)
			(stroke
				(width 0.1)
				(type default)
			)
			(layer "B.Fab")
		)
		(pad "1" smd circle
			(at 0.40005 0 270)
			(size 0 0)
			(layers "B.Cu" "B.Mask" "B.Paste")
			(net "P0V9_CPU0_RT2_2A")
		)
		(pad "2" smd circle
			(at -0.40005 0 270)
			(size 0 0)
			(layers "B.Cu" "B.Mask" "B.Paste")
			(net "GND")
		)
	)
	(footprint ""
		(layer "B.Cu")
		(at 125.389386 -250.892564)
		(property "Reference" "C2443"
			(at 0 0 0)
			(layer "B.SilkS")
			(hide yes)
			(effects
				(font
					(size 1.27 1.27)
				)
				(justify mirror)
			)
		)
		(property "Value" ""
			(at 0 0 0)
			(layer "B.Fab")
			(effects
				(font
					(size 1.27 1.27)
				)
				(justify mirror)
			)
		)
		(duplicate_pad_numbers_are_jumpers no)
		(fp_line
			(start -0.7874 -0.4064)
			(end -0.7874 0.4064)
			(stroke
				(width 0.1524)
				(type default)
			)
			(layer "B.SilkS")
		)
		(fp_line
			(start -0.7874 0.4064)
			(end 0.7874 0.4064)
			(stroke
				(width 0.1524)
				(type default)
			)
			(layer "B.SilkS")
		)
		(fp_line
			(start 0.7874 -0.4064)
			(end -0.7874 -0.4064)
			(stroke
				(width 0.1524)
				(type default)
			)
			(layer "B.SilkS")
		)
		(fp_line
			(start 0.7874 0.4064)
			(end 0.7874 -0.4064)
			(stroke
				(width 0.1524)
				(type default)
			)
			(layer "B.SilkS")
		)
		(fp_line
			(start -0.67945 -0.3048)
			(end -0.67945 0.3048)
			(stroke
				(width 0.1)
				(type default)
			)
			(layer "B.Fab")
		)
		(fp_line
			(start -0.67945 0.3048)
			(end -0.120396 0.3048)
			(stroke
				(width 0.1)
				(type default)
			)
			(layer "B.Fab")
		)
		(fp_line
			(start -0.12065 -0.3048)
			(end -0.67945 -0.3048)
			(stroke
				(width 0.1)
				(type default)
			)
			(layer "B.Fab")
		)
		(fp_line
			(start -0.12065 -0.2794)
			(end -0.12065 -0.3048)
			(stroke
				(width 0.1)
				(type default)
			)
			(layer "B.Fab")
		)
		(fp_line
			(start -0.120396 0.2794)
			(end 0.12065 0.2794)
			(stroke
				(width 0.1)
				(type default)
			)
			(layer "B.Fab")
		)
		(fp_line
			(start -0.120396 0.3048)
			(end -0.120396 0.2794)
			(stroke
				(width 0.1)
				(type default)
			)
			(layer "B.Fab")
		)
		(fp_line
			(start 0.12065 -0.305054)
			(end 0.12065 -0.2794)
			(stroke
				(width 0.1)
				(type default)
			)
			(layer "B.Fab")
		)
		(fp_line
			(start 0.12065 -0.2794)
			(end -0.12065 -0.2794)
			(stroke
				(width 0.1)
				(type default)
			)
			(layer "B.Fab")
		)
		(fp_line
			(start 0.12065 0.2794)
			(end 0.12065 0.3048)
			(stroke
				(width 0.1)
				(type default)
			)
			(layer "B.Fab")
		)
		(fp_line
			(start 0.12065 0.3048)
			(end 0.67945 0.3048)
			(stroke
				(width 0.1)
				(type default)
			)
			(layer "B.Fab")
		)
		(fp_line
			(start 0.67945 -0.305054)
			(end 0.12065 -0.305054)
			(stroke
				(width 0.1)
				(type default)
			)
			(layer "B.Fab")
		)
		(fp_line
			(start 0.67945 0.3048)
			(end 0.67945 -0.305054)
			(stroke
				(width 0.1)
				(type default)
			)
			(layer "B.Fab")
		)
		(pad "1" smd circle
			(at 0.40005 0 180)
			(size 0 0)
			(layers "B.Cu" "B.Mask" "B.Paste")
			(net "PVDDCR_SOC_P1")
		)
		(pad "2" smd circle
			(at -0.40005 0 180)
			(size 0 0)
			(layers "B.Cu" "B.Mask" "B.Paste")
			(net "GND")
		)
	)
	(footprint ""
		(layer "B.Cu")
		(at 345.122246 -416.899344 90)
		(property "Reference" "C6560"
			(at 0 0 90)
			(layer "B.SilkS")
			(hide yes)
			(effects
				(font
					(size 1.27 1.27)
				)
				(justify mirror)
			)
		)
		(property "Value" ""
			(at 0 0 90)
			(layer "B.Fab")
			(effects
				(font
					(size 1.27 1.27)
				)
				(justify mirror)
			)
		)
		(duplicate_pad_numbers_are_jumpers no)
		(fp_line
			(start 0.299974 -0.150114)
			(end -0.299974 -0.150114)
			(stroke
				(width 0.1)
				(type default)
			)
			(layer "B.Fab")
		)
		(fp_line
			(start -0.299974 -0.150114)
			(end -0.299974 0.150114)
			(stroke
				(width 0.1)
				(type default)
			)
			(layer "B.Fab")
		)
		(fp_line
			(start 0.299974 0.150114)
			(end 0.299974 -0.150114)
			(stroke
				(width 0.1)
				(type default)
			)
			(layer "B.Fab")
		)
		(fp_line
			(start -0.299974 0.150114)
			(end 0.299974 0.150114)
			(stroke
				(width 0.1)
				(type default)
			)
			(layer "B.Fab")
		)
		(pad "1" smd rect
			(at 0.2667 0 270)
			(size 0.3048 0.381)
			(layers "B.Cu" "B.Mask" "B.Paste")
			(net "P5E_CPU0_P1_TX_BUF_C_DN<13>")
		)
		(pad "2" smd rect
			(at -0.2667 0 270)
			(size 0.3048 0.381)
			(layers "B.Cu" "B.Mask" "B.Paste")
			(net "P5E_CPU0_P1_TX_BUF_DN<13>")
		)
	)
)
